(kicad_pcb
	(version 20241229)
	(generator "pcbnew")
	(generator_version "9.0")
	(general
		(thickness 1.6296)
		(legacy_teardrops no)
	)
	(paper "A3")
	(title_block
		(title "Thunderbolt to 10GbE adapter")
		(date "2026-04-21")
		(rev "1.1.0")
		(company "Antmicro Ltd")
		(comment 1 "www.antmicro.com")
		(comment 9 "footprints 327-332 of 703")
	)
	(layers
		(0 "F.Cu" signal)
		(4 "In1.Cu" signal)
		(6 "In2.Cu" signal)
		(8 "In3.Cu" signal)
		(10 "In4.Cu" signal)
		(12 "In5.Cu" signal)
		(14 "In6.Cu" signal)
		(2 "B.Cu" signal)
		(9 "F.Adhes" user "F.Adhesive")
		(11 "B.Adhes" user "B.Adhesive")
		(13 "F.Paste" user)
		(15 "B.Paste" user)
		(5 "F.SilkS" user "F.Silkscreen")
		(7 "B.SilkS" user "B.Silkscreen")
		(1 "F.Mask" user)
		(3 "B.Mask" user)
		(17 "Dwgs.User" user "User.Drawings")
		(19 "Cmts.User" user "User.Comments")
		(21 "Eco1.User" user "User.Eco1")
		(23 "Eco2.User" user "User.Eco2")
		(25 "Edge.Cuts" user)
		(27 "Margin" user)
		(31 "F.CrtYd" user "F.Courtyard")
		(29 "B.CrtYd" user "B.Courtyard")
		(35 "F.Fab" user)
		(33 "B.Fab" user)
	)
	(footprint "antmicro-footprints:R_0402_1005Metric"
		(layer "F.Cu")
		(at 160 46.3 -90)
		(descr "Resistor SMD 0402")
		(tags "resistor SMD 0402")
		(property "Reference" "R230"
			(at 1.9 -6.3 270)
			(layer "F.SilkS")
			(effects
				(font
					(size 0.7 0.7)
					(thickness 0.15)
				)
				(justify left bottom)
			)
		)
		(property "Value" "R_100k_0402"
			(at -1.011843 1.772047 270)
			(layer "F.Fab")
			(effects
				(font
					(size 0.7 0.7)
					(thickness 0.15)
				)
				(justify left bottom)
			)
		)
		(property "Datasheet" "https://www.bourns.com/docs/product-datasheets/cr.pdf"
			(at 0 0 270)
			(layer "F.Fab")
			(hide yes)
			(effects
				(font
					(size 1.27 1.27)
					(thickness 0.15)
				)
			)
		)
		(property "Description" "SMD Chip Resistor, 100 kohm, ± 1%, 62.5 mW, 0402 [1005 Metric], Thick Film, General Purpose"
			(at 0 0 270)
			(layer "F.Fab")
			(hide yes)
			(effects
				(font
					(size 1.27 1.27)
					(thickness 0.15)
				)
			)
		)
		(property "MPN" "CR0402-FX-1003GLF"
			(at 0 0 270)
			(unlocked yes)
			(layer "F.Fab")
			(hide yes)
			(effects
				(font
					(size 1 1)
					(thickness 0.15)
				)
			)
		)
		(property "Manufacturer" "Bourns"
			(at 0 0 270)
			(unlocked yes)
			(layer "F.Fab")
			(hide yes)
			(effects
				(font
					(size 1 1)
					(thickness 0.15)
				)
			)
		)
		(property "License" "Apache-2.0"
			(at 0 0 270)
			(unlocked yes)
			(layer "F.Fab")
			(hide yes)
			(effects
				(font
					(size 1 1)
					(thickness 0.15)
				)
			)
		)
		(property "Author" "Antmicro"
			(at 0 0 270)
			(unlocked yes)
			(layer "F.Fab")
			(hide yes)
			(effects
				(font
					(size 1 1)
					(thickness 0.15)
				)
			)
		)
		(property "Val" "100k"
			(at 0 0 270)
			(unlocked yes)
			(layer "F.Fab")
			(hide yes)
			(effects
				(font
					(size 1 1)
					(thickness 0.15)
				)
			)
		)
		(property "Tolerance" "1%"
			(at 0 0 270)
			(unlocked yes)
			(layer "F.Fab")
			(hide yes)
			(effects
				(font
					(size 1 1)
					(thickness 0.15)
				)
			)
		)
		(sheetname "/Power input/")
		(sheetfile "power_input.kicad_sch")
		(attr smd)
		(fp_rect
			(start -0.925 -0.47)
			(end 0.925 0.47)
			(stroke
				(width 0.05)
				(type default)
			)
			(fill no)
			(layer "F.CrtYd")
		)
		(fp_rect
			(start -0.5 -0.25)
			(end 0.5 0.25)
			(stroke
				(width 0.15)
				(type solid)
			)
			(fill no)
			(layer "F.Fab")
		)
		(fp_text user "Author: Antmicro"
			(at -0.95 4.169 270)
			(layer "F.Fab")
			(effects
				(font
					(size 0.7 0.7)
					(thickness 0.15)
				)
				(justify left bottom)
			)
		)
		(fp_text user "License: Apache-2.0"
			(at -0.95 5.169 270)
			(layer "F.Fab")
			(effects
				(font
					(size 0.7 0.7)
					(thickness 0.15)
				)
				(justify left bottom)
			)
		)
		(fp_text user "${REFERENCE}"
			(at -0.95 3.168 270)
			(layer "F.Fab")
			(effects
				(font
					(size 0.7 0.7)
					(thickness 0.15)
				)
				(justify left bottom)
			)
		)
		(pad "1" smd roundrect
			(at -0.48 0 270)
			(size 0.59 0.64)
			(layers "F.Cu" "F.Mask" "F.Paste")
			(roundrect_rratio 0.25)
			(net 23 "GND")
			(pintype "passive")
		)
		(pad "2" smd roundrect
			(at 0.48 0 270)
			(size 0.59 0.64)
			(layers "F.Cu" "F.Mask" "F.Paste")
			(roundrect_rratio 0.25)
			(net 390 "/Power input/5V_MODE2")
			(pintype "passive")
		)
	)
	(footprint "antmicro-footprints:R_0402_1005Metric"
		(layer "F.Cu")
		(at 156.205 65.174999 90)
		(descr "Resistor SMD 0402")
		(tags "resistor SMD 0402")
		(property "Reference" "R161"
			(at 2.374999 0.095001 90)
			(layer "F.SilkS")
			(effects
				(font
					(size 0.7 0.7)
					(thickness 0.15)
				)
			)
		)
		(property "Value" "R_10k_0402"
			(at -1.011843 1.772047 90)
			(layer "F.Fab")
			(effects
				(font
					(size 0.7 0.7)
					(thickness 0.15)
				)
				(justify left bottom)
			)
		)
		(property "Datasheet" "https://www.bourns.com/docs/product-datasheets/cr.pdf"
			(at 0 0 90)
			(layer "F.Fab")
			(hide yes)
			(effects
				(font
					(size 1.27 1.27)
					(thickness 0.15)
				)
			)
		)
		(property "Description" "SMD Chip Resistor, 10 kohm, ± 1%, 62.5 mW, 0402 [1005 Metric], Thick Film, General Purpose"
			(at 0 0 90)
			(layer "F.Fab")
			(hide yes)
			(effects
				(font
					(size 1.27 1.27)
					(thickness 0.15)
				)
			)
		)
		(property "MPN" "CR0402-FX-1002GLF"
			(at 0 0 90)
			(unlocked yes)
			(layer "F.Fab")
			(hide yes)
			(effects
				(font
					(size 1 1)
					(thickness 0.15)
				)
			)
		)
		(property "Manufacturer" "Bourns"
			(at 0 0 90)
			(unlocked yes)
			(layer "F.Fab")
			(hide yes)
			(effects
				(font
					(size 1 1)
					(thickness 0.15)
				)
			)
		)
		(property "License" "Apache-2.0"
			(at 0 0 90)
			(unlocked yes)
			(layer "F.Fab")
			(hide yes)
			(effects
				(font
					(size 1 1)
					(thickness 0.15)
				)
			)
		)
		(property "Author" "Antmicro"
			(at 0 0 90)
			(unlocked yes)
			(layer "F.Fab")
			(hide yes)
			(effects
				(font
					(size 1 1)
					(thickness 0.15)
				)
			)
		)
		(property "Val" "10k"
			(at 0 0 90)
			(unlocked yes)
			(layer "F.Fab")
			(hide yes)
			(effects
				(font
					(size 1 1)
					(thickness 0.15)
				)
			)
		)
		(property "Tolerance" "1%"
			(at 0 0 90)
			(unlocked yes)
			(layer "F.Fab")
			(hide yes)
			(effects
				(font
					(size 1 1)
					(thickness 0.15)
				)
			)
		)
		(sheetname "/X710-AT2 Misc/")
		(sheetfile "x710-at2-mics.kicad_sch")
		(attr smd)
		(fp_rect
			(start -0.925 -0.47)
			(end 0.925 0.47)
			(stroke
				(width 0.05)
				(type default)
			)
			(fill no)
			(layer "F.CrtYd")
		)
		(fp_rect
			(start -0.5 -0.25)
			(end 0.5 0.25)
			(stroke
				(width 0.15)
				(type solid)
			)
			(fill no)
			(layer "F.Fab")
		)
		(fp_text user "Author: Antmicro"
			(at -0.95 4.169 90)
			(layer "F.Fab")
			(effects
				(font
					(size 0.7 0.7)
					(thickness 0.15)
				)
				(justify left bottom)
			)
		)
		(fp_text user "License: Apache-2.0"
			(at -0.95 5.169 90)
			(layer "F.Fab")
			(effects
				(font
					(size 0.7 0.7)
					(thickness 0.15)
				)
				(justify left bottom)
			)
		)
		(fp_text user "${REFERENCE}"
			(at -0.95 3.168 90)
			(layer "F.Fab")
			(effects
				(font
					(size 0.7 0.7)
					(thickness 0.15)
				)
				(justify left bottom)
			)
		)
		(pad "1" smd roundrect
			(at -0.48 0 90)
			(size 0.59 0.64)
			(layers "F.Cu" "F.Mask" "F.Paste")
			(roundrect_rratio 0.25)
			(net 23 "GND")
			(pintype "passive")
		)
		(pad "2" smd roundrect
			(at 0.48 0 90)
			(size 0.59 0.64)
			(layers "F.Cu" "F.Mask" "F.Paste")
			(roundrect_rratio 0.25)
			(net 145 "/X710-AT2 Misc/NCSI.ARB_IN")
			(pintype "passive")
		)
	)
	(footprint "antmicro-footprints:C_0402_1005Metric"
		(layer "F.Cu")
		(at 117.8 127 180)
		(descr "Capacitor SMD 0402")
		(tags "capacitor SMD 0402")
		(property "Reference" "C47"
			(at -0.8 -0.2 180)
			(layer "F.SilkS")
			(effects
				(font
					(size 0.7 0.7)
					(thickness 0.15)
				)
				(justify left bottom)
			)
		)
		(property "Value" "C_220n_0402"
			(at -1.022927 2.155213 180)
			(layer "F.Fab")
			(effects
				(font
					(size 0.7 0.7)
					(thickness 0.15)
				)
				(justify left bottom)
			)
		)
		(property "Datasheet" "https://www.yageo.com/en/Chart/Download/pdf/CC0402KRX5R6BB224"
			(at 0 0 180)
			(layer "F.Fab")
			(hide yes)
			(effects
				(font
					(size 1.27 1.27)
					(thickness 0.15)
				)
			)
		)
		(property "Description" "SMD Multilayer Ceramic Capacitor, 0.22 µF, 10 V, 0402 [1005 Metric], ± 10%, X5R, CC Series"
			(at 0 0 180)
			(layer "F.Fab")
			(hide yes)
			(effects
				(font
					(size 1.27 1.27)
					(thickness 0.15)
				)
			)
		)
		(property "MPN" "CC0402KRX5R6BB224"
			(at 0 0 180)
			(unlocked yes)
			(layer "F.Fab")
			(hide yes)
			(effects
				(font
					(size 1 1)
					(thickness 0.15)
				)
			)
		)
		(property "Manufacturer" "YAGEO"
			(at 0 0 180)
			(unlocked yes)
			(layer "F.Fab")
			(hide yes)
			(effects
				(font
					(size 1 1)
					(thickness 0.15)
				)
			)
		)
		(property "License" "Apache-2.0"
			(at 0 0 180)
			(unlocked yes)
			(layer "F.Fab")
			(hide yes)
			(effects
				(font
					(size 1 1)
					(thickness 0.15)
				)
			)
		)
		(property "Val" "220n"
			(at 0 0 180)
			(unlocked yes)
			(layer "F.Fab")
			(hide yes)
			(effects
				(font
					(size 1 1)
					(thickness 0.15)
				)
			)
		)
		(property "Voltage" ""
			(at 0 0 180)
			(unlocked yes)
			(layer "F.Fab")
			(hide yes)
			(effects
				(font
					(size 1 1)
					(thickness 0.15)
				)
			)
		)
		(property "Dielectric" ""
			(at 0 0 180)
			(unlocked yes)
			(layer "F.Fab")
			(hide yes)
			(effects
				(font
					(size 1 1)
					(thickness 0.15)
				)
			)
		)
		(property "Author" "Antmicro"
			(at 0 0 180)
			(unlocked yes)
			(layer "F.Fab")
			(hide yes)
			(effects
				(font
					(size 1 1)
					(thickness 0.15)
				)
			)
		)
		(sheetname "/TB Controller/")
		(sheetfile "tb.kicad_sch")
		(attr smd)
		(fp_rect
			(start -0.925 -0.47)
			(end 0.925 0.47)
			(stroke
				(width 0.05)
				(type default)
			)
			(fill no)
			(layer "F.CrtYd")
		)
		(fp_line
			(start 0.504 0.248)
			(end -0.494 0.248)
			(stroke
				(width 0.15)
				(type solid)
			)
			(layer "F.Fab")
		)
		(fp_line
			(start 0.504 -0.25)
			(end 0.504 0.248)
			(stroke
				(width 0.15)
				(type solid)
			)
			(layer "F.Fab")
		)
		(fp_line
			(start -0.494 0.248)
			(end -0.494 -0.25)
			(stroke
				(width 0.15)
				(type solid)
			)
			(layer "F.Fab")
		)
		(fp_line
			(start -0.494 -0.25)
			(end 0.504 -0.25)
			(stroke
				(width 0.15)
				(type solid)
			)
			(layer "F.Fab")
		)
		(fp_text user "${REFERENCE}"
			(at -0.939 4.599 180)
			(layer "F.Fab")
			(effects
				(font
					(size 0.7 0.7)
					(thickness 0.15)
				)
				(justify left bottom)
			)
		)
		(fp_text user "Author: Antmicro"
			(at -0.939 3.399 180)
			(layer "F.Fab")
			(effects
				(font
					(size 0.7 0.7)
					(thickness 0.15)
				)
				(justify left bottom)
			)
		)
		(fp_text user "License: Apache-2.0"
			(at -0.939 5.799 180)
			(layer "F.Fab")
			(effects
				(font
					(size 0.7 0.7)
					(thickness 0.15)
				)
				(justify left bottom)
			)
		)
		(pad "1" smd roundrect
			(at -0.48 0 180)
			(size 0.59 0.64)
			(layers "F.Cu" "F.Mask" "F.Paste")
			(roundrect_rratio 0.25)
			(net 329 "/TB Controller/TB_PCIE_TX3_P")
			(pintype "passive")
		)
		(pad "2" smd roundrect
			(at 0.48 0 180)
			(size 0.59 0.64)
			(layers "F.Cu" "F.Mask" "F.Paste")
			(roundrect_rratio 0.25)
			(net 321 "/TB Controller/PCIex4.RX3+")
			(pintype "passive")
		)
	)
	(footprint "antmicro-footprints:R_0402_1005Metric"
		(layer "F.Cu")
		(at 143.849998 110.15 180)
		(descr "Resistor SMD 0402")
		(tags "resistor SMD 0402")
		(property "Reference" "R106"
			(at -15.349999 -17.25 180)
			(layer "F.SilkS")
			(effects
				(font
					(size 0.7 0.7)
					(thickness 0.15)
				)
			)
		)
		(property "Value" "R_20k_0402"
			(at -1.011843 1.772047 180)
			(layer "F.Fab")
			(effects
				(font
					(size 0.7 0.7)
					(thickness 0.15)
				)
				(justify left bottom)
			)
		)
		(property "Datasheet" "https://www.bourns.com/docs/product-datasheets/cr.pdf"
			(at 0 0 180)
			(layer "F.Fab")
			(hide yes)
			(effects
				(font
					(size 1.27 1.27)
					(thickness 0.15)
				)
			)
		)
		(property "Description" "SMD Chip Resistor, 20 kohm, ± 1%, 62.5 mW, 0402 [1005 Metric], Thick Film, General Purpose"
			(at 0 0 180)
			(layer "F.Fab")
			(hide yes)
			(effects
				(font
					(size 1.27 1.27)
					(thickness 0.15)
				)
			)
		)
		(property "MPN" "CR0402-FX-2002GLF"
			(at 0 0 180)
			(unlocked yes)
			(layer "F.Fab")
			(hide yes)
			(effects
				(font
					(size 1 1)
					(thickness 0.15)
				)
			)
		)
		(property "Manufacturer" "Bourns"
			(at 0 0 180)
			(unlocked yes)
			(layer "F.Fab")
			(hide yes)
			(effects
				(font
					(size 1 1)
					(thickness 0.15)
				)
			)
		)
		(property "License" "Apache-2.0"
			(at 0 0 180)
			(unlocked yes)
			(layer "F.Fab")
			(hide yes)
			(effects
				(font
					(size 1 1)
					(thickness 0.15)
				)
			)
		)
		(property "Author" "Antmicro"
			(at 0 0 180)
			(unlocked yes)
			(layer "F.Fab")
			(hide yes)
			(effects
				(font
					(size 1 1)
					(thickness 0.15)
				)
			)
		)
		(property "Val" "20k"
			(at 0 0 180)
			(unlocked yes)
			(layer "F.Fab")
			(hide yes)
			(effects
				(font
					(size 1 1)
					(thickness 0.15)
				)
			)
		)
		(property "Tolerance" "1%"
			(at 0 0 180)
			(unlocked yes)
			(layer "F.Fab")
			(hide yes)
			(effects
				(font
					(size 1 1)
					(thickness 0.15)
				)
			)
		)
		(sheetname "/X710 DCDC converters/")
		(sheetfile "DCDC_converters_X710.kicad_sch")
		(attr smd)
		(fp_rect
			(start -0.925 -0.47)
			(end 0.925 0.47)
			(stroke
				(width 0.05)
				(type default)
			)
			(fill no)
			(layer "F.CrtYd")
		)
		(fp_rect
			(start -0.5 -0.25)
			(end 0.5 0.25)
			(stroke
				(width 0.15)
				(type solid)
			)
			(fill no)
			(layer "F.Fab")
		)
		(fp_text user "License: Apache-2.0"
			(at -0.95 5.169 180)
			(layer "F.Fab")
			(effects
				(font
					(size 0.7 0.7)
					(thickness 0.15)
				)
				(justify left bottom)
			)
		)
		(fp_text user "${REFERENCE}"
			(at -0.95 3.168 180)
			(layer "F.Fab")
			(effects
				(font
					(size 0.7 0.7)
					(thickness 0.15)
				)
				(justify left bottom)
			)
		)
		(fp_text user "Author: Antmicro"
			(at -0.95 4.169 180)
			(layer "F.Fab")
			(effects
				(font
					(size 0.7 0.7)
					(thickness 0.15)
				)
				(justify left bottom)
			)
		)
		(pad "1" smd roundrect
			(at -0.48 0 180)
			(size 0.59 0.64)
			(layers "F.Cu" "F.Mask" "F.Paste")
			(roundrect_rratio 0.25)
			(net 342 "/X710 DCDC converters/DVDD_FB")
			(pintype "passive")
		)
		(pad "2" smd roundrect
			(at 0.48 0 180)
			(size 0.59 0.64)
			(layers "F.Cu" "F.Mask" "F.Paste")
			(roundrect_rratio 0.25)
			(net 341 "/X710 DCDC converters/+DVDD_OUT")
			(pintype "passive")
		)
	)
	(footprint "antmicro-footprints:Fiducial_1mm_Mask2mm"
		(layer "F.Cu")
		(at 125 47.5)
		(descr "Circular Fiducial, 1mm bare copper, 3mm soldermask opening")
		(tags "fiducial")
		(property "Reference" "FD1"
			(at -2.8 -1.1 0)
			(layer "F.SilkS")
			(effects
				(font
					(size 0.7 0.7)
					(thickness 0.15)
				)
				(justify left bottom)
			)
		)
		(property "Value" "Fiducial_1mm_Mask2mm"
			(at 0 2.2 0)
			(layer "F.Fab")
			(effects
				(font
					(size 0.7 0.7)
					(thickness 0.15)
				)
				(justify left bottom)
			)
		)
		(property "Description" "Fiducial mask"
			(at 0 0 0)
			(layer "F.Fab")
			(hide yes)
			(effects
				(font
					(size 1.27 1.27)
					(thickness 0.15)
				)
			)
		)
		(property "Author" "Antmicro"
			(at 0 0 0)
			(unlocked yes)
			(layer "F.Fab")
			(hide yes)
			(effects
				(font
					(size 1 1)
					(thickness 0.15)
				)
			)
		)
		(property "License" "Apache-2.0"
			(at 0 0 0)
			(unlocked yes)
			(layer "F.Fab")
			(hide yes)
			(effects
				(font
					(size 1 1)
					(thickness 0.15)
				)
			)
		)
		(sheetname "/")
		(sheetfile "thunderbolt-to-10gbe-adapter.kicad_sch")
		(attr exclude_from_pos_files exclude_from_bom)
		(fp_circle
			(center 0 0)
			(end 1.24 0)
			(stroke
				(width 0.05)
				(type solid)
			)
			(fill no)
			(layer "F.CrtYd")
		)
		(fp_circle
			(center 0 0)
			(end 0.999 0)
			(stroke
				(width 0.15)
				(type solid)
			)
			(fill no)
			(layer "F.Fab")
		)
		(fp_text user "Author: Antmicro"
			(at -1.25 5.803 0)
			(layer "F.Fab")
			(effects
				(font
					(size 0.7 0.7)
					(thickness 0.15)
				)
				(justify left bottom)
			)
		)
		(fp_text user "${REFERENCE}"
			(at -1.25 4.603 0)
			(layer "F.Fab")
			(effects
				(font
					(size 0.7 0.7)
					(thickness 0.15)
				)
				(justify left bottom)
			)
		)
		(fp_text user "License: Apache-2.0"
			(at -1.25 7.003 0)
			(layer "F.Fab")
			(effects
				(font
					(size 0.7 0.7)
					(thickness 0.15)
				)
				(justify left bottom)
			)
		)
		(pad "" smd circle
			(at 0 0)
			(size 1 1)
			(layers "F.Cu" "F.Mask")
			(solder_mask_margin 0.5)
			(clearance 0.5)
		)
	)
	(footprint "antmicro-footprints:R_0402_1005Metric"
		(layer "F.Cu")
		(at 129.52 94.2 180)
		(descr "Resistor SMD 0402")
		(tags "resistor SMD 0402")
		(property "Reference" "R99"
			(at -38.914999 9.199999 180)
			(layer "F.SilkS")
			(effects
				(font
					(size 0.7 0.7)
					(thickness 0.15)
				)
			)
		)
		(property "Value" "R_20k_0402"
			(at -1.011843 1.772047 180)
			(layer "F.Fab")
			(effects
				(font
					(size 0.7 0.7)
					(thickness 0.15)
				)
				(justify left bottom)
			)
		)
		(property "Datasheet" "https://www.bourns.com/docs/product-datasheets/cr.pdf"
			(at 0 0 180)
			(layer "F.Fab")
			(hide yes)
			(effects
				(font
					(size 1.27 1.27)
					(thickness 0.15)
				)
			)
		)
		(property "Description" "SMD Chip Resistor, 20 kohm, ± 1%, 62.5 mW, 0402 [1005 Metric], Thick Film, General Purpose"
			(at 0 0 180)
			(layer "F.Fab")
			(hide yes)
			(effects
				(font
					(size 1.27 1.27)
					(thickness 0.15)
				)
			)
		)
		(property "MPN" "CR0402-FX-2002GLF"
			(at 0 0 180)
			(unlocked yes)
			(layer "F.Fab")
			(hide yes)
			(effects
				(font
					(size 1 1)
					(thickness 0.15)
				)
			)
		)
		(property "Manufacturer" "Bourns"
			(at 0 0 180)
			(unlocked yes)
			(layer "F.Fab")
			(hide yes)
			(effects
				(font
					(size 1 1)
					(thickness 0.15)
				)
			)
		)
		(property "License" "Apache-2.0"
			(at 0 0 180)
			(unlocked yes)
			(layer "F.Fab")
			(hide yes)
			(effects
				(font
					(size 1 1)
					(thickness 0.15)
				)
			)
		)
		(property "Author" "Antmicro"
			(at 0 0 180)
			(unlocked yes)
			(layer "F.Fab")
			(hide yes)
			(effects
				(font
					(size 1 1)
					(thickness 0.15)
				)
			)
		)
		(property "Val" "20k"
			(at 0 0 180)
			(unlocked yes)
			(layer "F.Fab")
			(hide yes)
			(effects
				(font
					(size 1 1)
					(thickness 0.15)
				)
			)
		)
		(property "Tolerance" "1%"
			(at 0 0 180)
			(unlocked yes)
			(layer "F.Fab")
			(hide yes)
			(effects
				(font
					(size 1 1)
					(thickness 0.15)
				)
			)
		)
		(sheetname "/X710 DCDC converters/")
		(sheetfile "DCDC_converters_X710.kicad_sch")
		(attr smd)
		(fp_rect
			(start -0.925 -0.47)
			(end 0.925 0.47)
			(stroke
				(width 0.05)
				(type default)
			)
			(fill no)
			(layer "F.CrtYd")
		)
		(fp_rect
			(start -0.5 -0.25)
			(end 0.5 0.25)
			(stroke
				(width 0.15)
				(type solid)
			)
			(fill no)
			(layer "F.Fab")
		)
		(fp_text user "License: Apache-2.0"
			(at -0.95 5.169 180)
			(layer "F.Fab")
			(effects
				(font
					(size 0.7 0.7)
					(thickness 0.15)
				)
				(justify left bottom)
			)
		)
		(fp_text user "${REFERENCE}"
			(at -0.95 3.168 180)
			(layer "F.Fab")
			(effects
				(font
					(size 0.7 0.7)
					(thickness 0.15)
				)
				(justify left bottom)
			)
		)
		(fp_text user "Author: Antmicro"
			(at -0.95 4.169 180)
			(layer "F.Fab")
			(effects
				(font
					(size 0.7 0.7)
					(thickness 0.15)
				)
				(justify left bottom)
			)
		)
		(pad "1" smd roundrect
			(at -0.48 0 180)
			(size 0.59 0.64)
			(layers "F.Cu" "F.Mask" "F.Paste")
			(roundrect_rratio 0.25)
			(net 23 "GND")
			(pintype "passive")
		)
		(pad "2" smd roundrect
			(at 0.48 0 180)
			(size 0.59 0.64)
			(layers "F.Cu" "F.Mask" "F.Paste")
			(roundrect_rratio 0.25)
			(net 333 "/X710 DCDC converters/3V3_FB")
			(pintype "passive")
		)
	)
)
